(kicad_pcb
	(version 20260206)
	(generator "pcbnew")
	(generator_version "10.0")
	(general
		(thickness 1.6)
		(legacy_teardrops no)
	)
	(paper "A4")
	(title_block
		(title "03242023_DA0F0TMBIJ0_F0T_Motherboard_J_brd_V01_OCP.brd")
		(comment 1 "Grand Teton / footprints 5842-5848 of 6105")
	)
	(layers
		(0 "F.Cu" signal "TOP")
		(4 "In1.Cu" signal "GND")
		(6 "In2.Cu" signal "IN1")
		(8 "In3.Cu" signal "GND1")
		(10 "In4.Cu" signal "IN2")
		(12 "In5.Cu" signal "GND2")
		(14 "In6.Cu" signal "IN3")
		(16 "In7.Cu" signal "GND3")
		(18 "In8.Cu" signal "VCC")
		(20 "In9.Cu" signal "VCC1")
		(22 "In10.Cu" signal "GND4")
		(24 "In11.Cu" signal "IN4")
		(26 "In12.Cu" signal "GND5")
		(28 "In13.Cu" signal "IN5")
		(30 "In14.Cu" signal "GND6")
		(32 "In15.Cu" signal "IN6")
		(34 "In16.Cu" signal "GND7")
		(2 "B.Cu" signal "BOTTOM")
		(9 "F.Adhes" user "F.Adhesive")
		(11 "B.Adhes" user "B.Adhesive")
		(13 "F.Paste" user "Package Geometry/Pastemask Top")
		(15 "B.Paste" user "Package Geometry/Pastemask Bottom")
		(5 "F.SilkS" user "Ref Des/Silkscreen Top")
		(7 "B.SilkS" user "Ref Des/Silkscreen Bottom")
		(1 "F.Mask" user "Board Geometry/Soldermask Top")
		(3 "B.Mask" user "Board Geometry/Soldermask Bottom")
		(17 "Dwgs.User" user "User.Drawings")
		(19 "Cmts.User" user "User.Comments")
		(21 "Eco1.User" user "User.Eco1")
		(23 "Eco2.User" user "User.Eco2")
		(25 "Edge.Cuts" user "Board Geometry/Outline")
		(27 "Margin" user)
		(31 "F.CrtYd" user "Package Geometry/Place Bound Top")
		(29 "B.CrtYd" user "Package Geometry/Place Bound Bottom")
		(35 "F.Fab" user "Ref Des/Assembly Top")
		(33 "B.Fab" user "Ref Des/Assembly Bottom")
	)
	(footprint ""
		(layer "B.Cu")
		(at 309.558182 -32.243268 180)
		(property "Reference" "R1299"
			(at 0 0 0)
			(layer "B.SilkS")
			(hide yes)
			(effects
				(font
					(size 1.27 1.27)
				)
				(justify mirror)
			)
		)
		(property "Value" ""
			(at 0 0 0)
			(layer "B.Fab")
			(effects
				(font
					(size 1.27 1.27)
				)
				(justify mirror)
			)
		)
		(duplicate_pad_numbers_are_jumpers no)
		(fp_line
			(start 0.7874 0.4064)
			(end 0.7874 -0.4064)
			(stroke
				(width 0.1524)
				(type default)
			)
			(layer "B.SilkS")
		)
		(fp_line
			(start 0.7874 -0.4064)
			(end -0.7874 -0.4064)
			(stroke
				(width 0.1524)
				(type default)
			)
			(layer "B.SilkS")
		)
		(fp_line
			(start -0.7874 0.4064)
			(end 0.7874 0.4064)
			(stroke
				(width 0.1524)
				(type default)
			)
			(layer "B.SilkS")
		)
		(fp_line
			(start -0.7874 -0.4064)
			(end -0.7874 0.4064)
			(stroke
				(width 0.1524)
				(type default)
			)
			(layer "B.SilkS")
		)
		(fp_line
			(start 0.67945 0.3048)
			(end 0.67945 -0.305054)
			(stroke
				(width 0.1)
				(type default)
			)
			(layer "B.Fab")
		)
		(fp_line
			(start 0.67945 -0.305054)
			(end 0.12065 -0.305054)
			(stroke
				(width 0.1)
				(type default)
			)
			(layer "B.Fab")
		)
		(fp_line
			(start 0.12065 0.3048)
			(end 0.67945 0.3048)
			(stroke
				(width 0.1)
				(type default)
			)
			(layer "B.Fab")
		)
		(fp_line
			(start 0.12065 0.2794)
			(end 0.12065 0.3048)
			(stroke
				(width 0.1)
				(type default)
			)
			(layer "B.Fab")
		)
		(fp_line
			(start 0.12065 -0.2794)
			(end -0.12065 -0.2794)
			(stroke
				(width 0.1)
				(type default)
			)
			(layer "B.Fab")
		)
		(fp_line
			(start 0.12065 -0.305054)
			(end 0.12065 -0.2794)
			(stroke
				(width 0.1)
				(type default)
			)
			(layer "B.Fab")
		)
		(fp_line
			(start -0.120396 0.3048)
			(end -0.120396 0.2794)
			(stroke
				(width 0.1)
				(type default)
			)
			(layer "B.Fab")
		)
		(fp_line
			(start -0.120396 0.2794)
			(end 0.12065 0.2794)
			(stroke
				(width 0.1)
				(type default)
			)
			(layer "B.Fab")
		)
		(fp_line
			(start -0.12065 -0.2794)
			(end -0.12065 -0.3048)
			(stroke
				(width 0.1)
				(type default)
			)
			(layer "B.Fab")
		)
		(fp_line
			(start -0.12065 -0.3048)
			(end -0.67945 -0.3048)
			(stroke
				(width 0.1)
				(type default)
			)
			(layer "B.Fab")
		)
		(fp_line
			(start -0.67945 0.3048)
			(end -0.120396 0.3048)
			(stroke
				(width 0.1)
				(type default)
			)
			(layer "B.Fab")
		)
		(fp_line
			(start -0.67945 -0.3048)
			(end -0.67945 0.3048)
			(stroke
				(width 0.1)
				(type default)
			)
			(layer "B.Fab")
		)
		(pad "1" smd circle
			(at 0.40005 0)
			(size 0 0)
			(layers "B.Cu" "B.Mask" "B.Paste")
			(net "FM_MFG_MODE")
		)
		(pad "2" smd circle
			(at -0.40005 0)
			(size 0 0)
			(layers "B.Cu" "B.Mask" "B.Paste")
			(net "GND")
		)
	)
	(footprint ""
		(layer "B.Cu")
		(at 168.475152 -344.941906 -90)
		(property "Reference" "PC410_P1_1"
			(at 0 0 90)
			(layer "B.SilkS")
			(hide yes)
			(effects
				(font
					(size 1.27 1.27)
				)
				(justify mirror)
			)
		)
		(property "Value" ""
			(at 0 0 90)
			(layer "B.Fab")
			(effects
				(font
					(size 1.27 1.27)
				)
				(justify mirror)
			)
		)
		(duplicate_pad_numbers_are_jumpers no)
		(fp_line
			(start -1.524 0.762)
			(end 1.524 0.762)
			(stroke
				(width 0.1524)
				(type default)
			)
			(layer "B.SilkS")
		)
		(fp_line
			(start 1.524 0.762)
			(end 1.524 -0.762)
			(stroke
				(width 0.1524)
				(type default)
			)
			(layer "B.SilkS")
		)
		(fp_line
			(start -1.524 -0.762)
			(end -1.524 0.762)
			(stroke
				(width 0.1524)
				(type default)
			)
			(layer "B.SilkS")
		)
		(fp_line
			(start 1.524 -0.762)
			(end -1.524 -0.762)
			(stroke
				(width 0.1524)
				(type default)
			)
			(layer "B.SilkS")
		)
		(fp_line
			(start -1.1049 0.724916)
			(end -1.1049 -0.724916)
			(stroke
				(width 0.1)
				(type default)
			)
			(layer "B.Fab")
		)
		(fp_line
			(start 1.1049 0.724916)
			(end -1.1049 0.724916)
			(stroke
				(width 0.1)
				(type default)
			)
			(layer "B.Fab")
		)
		(fp_line
			(start -1.1049 -0.724916)
			(end 1.1049 -0.724916)
			(stroke
				(width 0.1)
				(type default)
			)
			(layer "B.Fab")
		)
		(fp_line
			(start 1.1049 -0.724916)
			(end 1.1049 0.724916)
			(stroke
				(width 0.1)
				(type default)
			)
			(layer "B.Fab")
		)
		(pad "1" smd rect
			(at 0.889 0 270)
			(size 1.016 1.27)
			(layers "B.Cu" "B.Mask" "B.Paste")
			(net "PVCCFA_EHV_FIVRA_CPU1")
		)
		(pad "2" smd rect
			(at -0.889 0 270)
			(size 1.016 1.27)
			(layers "B.Cu" "B.Mask" "B.Paste")
			(net "GND")
		)
	)
	(footprint ""
		(layer "B.Cu")
		(at 23.240746 -319.268856 180)
		(property "Reference" "C62"
			(at 0 0 0)
			(layer "B.SilkS")
			(hide yes)
			(effects
				(font
					(size 1.27 1.27)
				)
				(justify mirror)
			)
		)
		(property "Value" ""
			(at 0 0 0)
			(layer "B.Fab")
			(effects
				(font
					(size 1.27 1.27)
				)
				(justify mirror)
			)
		)
		(duplicate_pad_numbers_are_jumpers no)
		(fp_line
			(start 0.7874 0.4064)
			(end 0.7874 -0.4064)
			(stroke
				(width 0.1524)
				(type default)
			)
			(layer "B.SilkS")
		)
		(fp_line
			(start 0.7874 -0.4064)
			(end -0.7874 -0.4064)
			(stroke
				(width 0.1524)
				(type default)
			)
			(layer "B.SilkS")
		)
		(fp_line
			(start -0.7874 0.4064)
			(end 0.7874 0.4064)
			(stroke
				(width 0.1524)
				(type default)
			)
			(layer "B.SilkS")
		)
		(fp_line
			(start -0.7874 -0.4064)
			(end -0.7874 0.4064)
			(stroke
				(width 0.1524)
				(type default)
			)
			(layer "B.SilkS")
		)
		(fp_line
			(start 0.67945 0.3048)
			(end 0.67945 -0.305054)
			(stroke
				(width 0.1)
				(type default)
			)
			(layer "B.Fab")
		)
		(fp_line
			(start 0.67945 -0.305054)
			(end 0.12065 -0.305054)
			(stroke
				(width 0.1)
				(type default)
			)
			(layer "B.Fab")
		)
		(fp_line
			(start 0.12065 0.3048)
			(end 0.67945 0.3048)
			(stroke
				(width 0.1)
				(type default)
			)
			(layer "B.Fab")
		)
		(fp_line
			(start 0.12065 0.2794)
			(end 0.12065 0.3048)
			(stroke
				(width 0.1)
				(type default)
			)
			(layer "B.Fab")
		)
		(fp_line
			(start 0.12065 -0.2794)
			(end -0.12065 -0.2794)
			(stroke
				(width 0.1)
				(type default)
			)
			(layer "B.Fab")
		)
		(fp_line
			(start 0.12065 -0.305054)
			(end 0.12065 -0.2794)
			(stroke
				(width 0.1)
				(type default)
			)
			(layer "B.Fab")
		)
		(fp_line
			(start -0.120396 0.3048)
			(end -0.120396 0.2794)
			(stroke
				(width 0.1)
				(type default)
			)
			(layer "B.Fab")
		)
		(fp_line
			(start -0.120396 0.2794)
			(end 0.12065 0.2794)
			(stroke
				(width 0.1)
				(type default)
			)
			(layer "B.Fab")
		)
		(fp_line
			(start -0.12065 -0.2794)
			(end -0.12065 -0.3048)
			(stroke
				(width 0.1)
				(type default)
			)
			(layer "B.Fab")
		)
		(fp_line
			(start -0.12065 -0.3048)
			(end -0.67945 -0.3048)
			(stroke
				(width 0.1)
				(type default)
			)
			(layer "B.Fab")
		)
		(fp_line
			(start -0.67945 0.3048)
			(end -0.120396 0.3048)
			(stroke
				(width 0.1)
				(type default)
			)
			(layer "B.Fab")
		)
		(fp_line
			(start -0.67945 -0.3048)
			(end -0.67945 0.3048)
			(stroke
				(width 0.1)
				(type default)
			)
			(layer "B.Fab")
		)
		(pad "1" smd circle
			(at 0.40005 0)
			(size 0 0)
			(layers "B.Cu" "B.Mask" "B.Paste")
			(net "P3V3_AUX")
		)
		(pad "2" smd circle
			(at -0.40005 0)
			(size 0 0)
			(layers "B.Cu" "B.Mask" "B.Paste")
			(net "GND")
		)
	)
	(footprint ""
		(layer "B.Cu")
		(at 315.110622 -51.171348)
		(property "Reference" "R1339"
			(at 0 0 0)
			(layer "B.SilkS")
			(hide yes)
			(effects
				(font
					(size 1.27 1.27)
				)
				(justify mirror)
			)
		)
		(property "Value" ""
			(at 0 0 0)
			(layer "B.Fab")
			(effects
				(font
					(size 1.27 1.27)
				)
				(justify mirror)
			)
		)
		(duplicate_pad_numbers_are_jumpers no)
		(fp_line
			(start -0.7874 -0.4064)
			(end -0.7874 0.4064)
			(stroke
				(width 0.1524)
				(type default)
			)
			(layer "B.SilkS")
		)
		(fp_line
			(start -0.7874 0.4064)
			(end 0.7874 0.4064)
			(stroke
				(width 0.1524)
				(type default)
			)
			(layer "B.SilkS")
		)
		(fp_line
			(start 0.7874 -0.4064)
			(end -0.7874 -0.4064)
			(stroke
				(width 0.1524)
				(type default)
			)
			(layer "B.SilkS")
		)
		(fp_line
			(start 0.7874 0.4064)
			(end 0.7874 -0.4064)
			(stroke
				(width 0.1524)
				(type default)
			)
			(layer "B.SilkS")
		)
		(fp_line
			(start -0.67945 -0.3048)
			(end -0.67945 0.3048)
			(stroke
				(width 0.1)
				(type default)
			)
			(layer "B.Fab")
		)
		(fp_line
			(start -0.67945 0.3048)
			(end -0.120396 0.3048)
			(stroke
				(width 0.1)
				(type default)
			)
			(layer "B.Fab")
		)
		(fp_line
			(start -0.12065 -0.3048)
			(end -0.67945 -0.3048)
			(stroke
				(width 0.1)
				(type default)
			)
			(layer "B.Fab")
		)
		(fp_line
			(start -0.12065 -0.2794)
			(end -0.12065 -0.3048)
			(stroke
				(width 0.1)
				(type default)
			)
			(layer "B.Fab")
		)
		(fp_line
			(start -0.120396 0.2794)
			(end 0.12065 0.2794)
			(stroke
				(width 0.1)
				(type default)
			)
			(layer "B.Fab")
		)
		(fp_line
			(start -0.120396 0.3048)
			(end -0.120396 0.2794)
			(stroke
				(width 0.1)
				(type default)
			)
			(layer "B.Fab")
		)
		(fp_line
			(start 0.12065 -0.305054)
			(end 0.12065 -0.2794)
			(stroke
				(width 0.1)
				(type default)
			)
			(layer "B.Fab")
		)
		(fp_line
			(start 0.12065 -0.2794)
			(end -0.12065 -0.2794)
			(stroke
				(width 0.1)
				(type default)
			)
			(layer "B.Fab")
		)
		(fp_line
			(start 0.12065 0.2794)
			(end 0.12065 0.3048)
			(stroke
				(width 0.1)
				(type default)
			)
			(layer "B.Fab")
		)
		(fp_line
			(start 0.12065 0.3048)
			(end 0.67945 0.3048)
			(stroke
				(width 0.1)
				(type default)
			)
			(layer "B.Fab")
		)
		(fp_line
			(start 0.67945 -0.305054)
			(end 0.12065 -0.305054)
			(stroke
				(width 0.1)
				(type default)
			)
			(layer "B.Fab")
		)
		(fp_line
			(start 0.67945 0.3048)
			(end 0.67945 -0.305054)
			(stroke
				(width 0.1)
				(type default)
			)
			(layer "B.Fab")
		)
		(pad "1" smd circle
			(at 0.40005 0 180)
			(size 0 0)
			(layers "B.Cu" "B.Mask" "B.Paste")
			(net "P3V3_AUX")
		)
		(pad "2" smd circle
			(at -0.40005 0 180)
			(size 0 0)
			(layers "B.Cu" "B.Mask" "B.Paste")
			(net "FM_BIOS_IMAGE_SWAP_N")
		)
	)
	(footprint ""
		(layer "B.Cu")
		(at 246.984266 -128.343914 -90)
		(property "Reference" "R570"
			(at 0 0 90)
			(layer "B.SilkS")
			(hide yes)
			(effects
				(font
					(size 1.27 1.27)
				)
				(justify mirror)
			)
		)
		(property "Value" ""
			(at 0 0 90)
			(layer "B.Fab")
			(effects
				(font
					(size 1.27 1.27)
				)
				(justify mirror)
			)
		)
		(duplicate_pad_numbers_are_jumpers no)
		(fp_line
			(start -0.7874 0.4064)
			(end 0.7874 0.4064)
			(stroke
				(width 0.1524)
				(type default)
			)
			(layer "B.SilkS")
		)
		(fp_line
			(start 0.7874 0.4064)
			(end 0.7874 -0.4064)
			(stroke
				(width 0.1524)
				(type default)
			)
			(layer "B.SilkS")
		)
		(fp_line
			(start -0.7874 -0.4064)
			(end -0.7874 0.4064)
			(stroke
				(width 0.1524)
				(type default)
			)
			(layer "B.SilkS")
		)
		(fp_line
			(start 0.7874 -0.4064)
			(end -0.7874 -0.4064)
			(stroke
				(width 0.1524)
				(type default)
			)
			(layer "B.SilkS")
		)
		(fp_line
			(start -0.67945 0.3048)
			(end -0.120396 0.3048)
			(stroke
				(width 0.1)
				(type default)
			)
			(layer "B.Fab")
		)
		(fp_line
			(start -0.120396 0.3048)
			(end -0.120396 0.2794)
			(stroke
				(width 0.1)
				(type default)
			)
			(layer "B.Fab")
		)
		(fp_line
			(start 0.12065 0.3048)
			(end 0.67945 0.3048)
			(stroke
				(width 0.1)
				(type default)
			)
			(layer "B.Fab")
		)
		(fp_line
			(start 0.67945 0.3048)
			(end 0.67945 -0.305054)
			(stroke
				(width 0.1)
				(type default)
			)
			(layer "B.Fab")
		)
		(fp_line
			(start -0.120396 0.2794)
			(end 0.12065 0.2794)
			(stroke
				(width 0.1)
				(type default)
			)
			(layer "B.Fab")
		)
		(fp_line
			(start 0.12065 0.2794)
			(end 0.12065 0.3048)
			(stroke
				(width 0.1)
				(type default)
			)
			(layer "B.Fab")
		)
		(fp_line
			(start -0.12065 -0.2794)
			(end -0.12065 -0.3048)
			(stroke
				(width 0.1)
				(type default)
			)
			(layer "B.Fab")
		)
		(fp_line
			(start 0.12065 -0.2794)
			(end -0.12065 -0.2794)
			(stroke
				(width 0.1)
				(type default)
			)
			(layer "B.Fab")
		)
		(fp_line
			(start -0.67945 -0.3048)
			(end -0.67945 0.3048)
			(stroke
				(width 0.1)
				(type default)
			)
			(layer "B.Fab")
		)
		(fp_line
			(start -0.12065 -0.3048)
			(end -0.67945 -0.3048)
			(stroke
				(width 0.1)
				(type default)
			)
			(layer "B.Fab")
		)
		(fp_line
			(start 0.12065 -0.305054)
			(end 0.12065 -0.2794)
			(stroke
				(width 0.1)
				(type default)
			)
			(layer "B.Fab")
		)
		(fp_line
			(start 0.67945 -0.305054)
			(end 0.12065 -0.305054)
			(stroke
				(width 0.1)
				(type default)
			)
			(layer "B.Fab")
		)
		(pad "1" smd circle
			(at 0.40005 0 90)
			(size 0 0)
			(layers "B.Cu" "B.Mask" "B.Paste")
			(net "PD_DB2000_SMB_SA0")
		)
		(pad "2" smd circle
			(at -0.40005 0 90)
			(size 0 0)
			(layers "B.Cu" "B.Mask" "B.Paste")
			(net "GND")
		)
	)
	(footprint ""
		(layer "B.Cu")
		(at 237.24108 -252.113288 90)
		(property "Reference" "C1886"
			(at 0 0 90)
			(layer "B.SilkS")
			(hide yes)
			(effects
				(font
					(size 1.27 1.27)
				)
				(justify mirror)
			)
		)
		(property "Value" ""
			(at 0 0 90)
			(layer "B.Fab")
			(effects
				(font
					(size 1.27 1.27)
				)
				(justify mirror)
			)
		)
		(duplicate_pad_numbers_are_jumpers no)
		(fp_line
			(start 0.7874 -0.4064)
			(end -0.7874 -0.4064)
			(stroke
				(width 0.1524)
				(type default)
			)
			(layer "B.SilkS")
		)
		(fp_line
			(start -0.7874 -0.4064)
			(end -0.7874 0.4064)
			(stroke
				(width 0.1524)
				(type default)
			)
			(layer "B.SilkS")
		)
		(fp_line
			(start 0.7874 0.4064)
			(end 0.7874 -0.4064)
			(stroke
				(width 0.1524)
				(type default)
			)
			(layer "B.SilkS")
		)
		(fp_line
			(start -0.7874 0.4064)
			(end 0.7874 0.4064)
			(stroke
				(width 0.1524)
				(type default)
			)
			(layer "B.SilkS")
		)
		(fp_line
			(start 0.67945 -0.305054)
			(end 0.12065 -0.305054)
			(stroke
				(width 0.1)
				(type default)
			)
			(layer "B.Fab")
		)
		(fp_line
			(start 0.12065 -0.305054)
			(end 0.12065 -0.2794)
			(stroke
				(width 0.1)
				(type default)
			)
			(layer "B.Fab")
		)
		(fp_line
			(start -0.12065 -0.3048)
			(end -0.67945 -0.3048)
			(stroke
				(width 0.1)
				(type default)
			)
			(layer "B.Fab")
		)
		(fp_line
			(start -0.67945 -0.3048)
			(end -0.67945 0.3048)
			(stroke
				(width 0.1)
				(type default)
			)
			(layer "B.Fab")
		)
		(fp_line
			(start 0.12065 -0.2794)
			(end -0.12065 -0.2794)
			(stroke
				(width 0.1)
				(type default)
			)
			(layer "B.Fab")
		)
		(fp_line
			(start -0.12065 -0.2794)
			(end -0.12065 -0.3048)
			(stroke
				(width 0.1)
				(type default)
			)
			(layer "B.Fab")
		)
		(fp_line
			(start 0.12065 0.2794)
			(end 0.12065 0.3048)
			(stroke
				(width 0.1)
				(type default)
			)
			(layer "B.Fab")
		)
		(fp_line
			(start -0.120396 0.2794)
			(end 0.12065 0.2794)
			(stroke
				(width 0.1)
				(type default)
			)
			(layer "B.Fab")
		)
		(fp_line
			(start 0.67945 0.3048)
			(end 0.67945 -0.305054)
			(stroke
				(width 0.1)
				(type default)
			)
			(layer "B.Fab")
		)
		(fp_line
			(start 0.12065 0.3048)
			(end 0.67945 0.3048)
			(stroke
				(width 0.1)
				(type default)
			)
			(layer "B.Fab")
		)
		(fp_line
			(start -0.120396 0.3048)
			(end -0.120396 0.2794)
			(stroke
				(width 0.1)
				(type default)
			)
			(layer "B.Fab")
		)
		(fp_line
			(start -0.67945 0.3048)
			(end -0.120396 0.3048)
			(stroke
				(width 0.1)
				(type default)
			)
			(layer "B.Fab")
		)
		(pad "1" smd circle
			(at 0.40005 0 270)
			(size 0 0)
			(layers "B.Cu" "B.Mask" "B.Paste")
			(net "VFG3P3_CLK_GEN")
		)
		(pad "2" smd circle
			(at -0.40005 0 270)
			(size 0 0)
			(layers "B.Cu" "B.Mask" "B.Paste")
			(net "GND")
		)
	)
	(footprint ""
		(layer "B.Cu")
		(at 189.001146 -321.554856 -90)
		(property "Reference" "C80"
			(at 0 0 90)
			(layer "B.SilkS")
			(hide yes)
			(effects
				(font
					(size 1.27 1.27)
				)
				(justify mirror)
			)
		)
		(property "Value" ""
			(at 0 0 90)
			(layer "B.Fab")
			(effects
				(font
					(size 1.27 1.27)
				)
				(justify mirror)
			)
		)
		(duplicate_pad_numbers_are_jumpers no)
		(fp_line
			(start -1.524 0.762)
			(end 1.524 0.762)
			(stroke
				(width 0.1524)
				(type default)
			)
			(layer "B.SilkS")
		)
		(fp_line
			(start 1.524 0.762)
			(end 1.524 -0.762)
			(stroke
				(width 0.1524)
				(type default)
			)
			(layer "B.SilkS")
		)
		(fp_line
			(start -1.524 -0.762)
			(end -1.524 0.762)
			(stroke
				(width 0.1524)
				(type default)
			)
			(layer "B.SilkS")
		)
		(fp_line
			(start 1.524 -0.762)
			(end -1.524 -0.762)
			(stroke
				(width 0.1524)
				(type default)
			)
			(layer "B.SilkS")
		)
		(fp_line
			(start -1.1049 0.724916)
			(end -1.1049 -0.724916)
			(stroke
				(width 0.1)
				(type default)
			)
			(layer "B.Fab")
		)
		(fp_line
			(start 1.1049 0.724916)
			(end -1.1049 0.724916)
			(stroke
				(width 0.1)
				(type default)
			)
			(layer "B.Fab")
		)
		(fp_line
			(start -1.1049 -0.724916)
			(end 1.1049 -0.724916)
			(stroke
				(width 0.1)
				(type default)
			)
			(layer "B.Fab")
		)
		(fp_line
			(start 1.1049 -0.724916)
			(end 1.1049 0.724916)
			(stroke
				(width 0.1)
				(type default)
			)
			(layer "B.Fab")
		)
		(pad "1" smd rect
			(at 0.889 0 270)
			(size 1.016 1.27)
			(layers "B.Cu" "B.Mask" "B.Paste")
			(net "P12V_S3_AUX_CPU1_NVDIMM")
		)
		(pad "2" smd rect
			(at -0.889 0 270)
			(size 1.016 1.27)
			(layers "B.Cu" "B.Mask" "B.Paste")
			(net "GND")
		)
	)
)
